# T6G (Grand Teton) — schematic netlist excerpt (pin names and nets, part order shuffled) for the footprints in the layout excerpt that follows; sources: Cadence DE-HDL packaged netlist, KiCad conversion of 04192023_DAF0TMB3IC0_F0TG_MB_C_brd_V02_OCP.brd

R1895  Q_RES  0 5% CHIP  pkg 0402LF  page 131 : A = OCP_SFF_PRSNTA_R_N ; B = GND
C2034  Q_CAP  0.1UF 25V 10% X7R  pkg 0402  page 234 : A = P3V3_AUX_USB_HUB ; B = GND

(kicad_pcb
	(version 20260206)
	(generator "pcbnew")
	(generator_version "10.0")
	(general
		(thickness 1.6)
		(legacy_teardrops no)
	)
	(paper "A4")
	(title_block
		(title "04192023_DAF0TMB3IC0_F0TG_MB_C_brd_V02_OCP.brd")
		(comment 1 "Grand Teton / footprints 4992-4993 of 8354")
	)
	(layers
		(0 "F.Cu" signal "TOP")
		(4 "In1.Cu" signal "GND")
		(6 "In2.Cu" signal "IN1")
		(8 "In3.Cu" signal "GND1")
		(10 "In4.Cu" signal "IN2")
		(12 "In5.Cu" signal "GND2")
		(14 "In6.Cu" signal "IN3")
		(16 "In7.Cu" signal "GND3")
		(18 "In8.Cu" signal "VCC")
		(20 "In9.Cu" signal "VCC1")
		(22 "In10.Cu" signal "GND4")
		(24 "In11.Cu" signal "IN4")
		(26 "In12.Cu" signal "GND5")
		(28 "In13.Cu" signal "IN5")
		(30 "In14.Cu" signal "GND6")
		(32 "In15.Cu" signal "IN6")
		(34 "In16.Cu" signal "GND7")
		(2 "B.Cu" signal "BOTTOM")
		(9 "F.Adhes" user "F.Adhesive")
		(11 "B.Adhes" user "B.Adhesive")
		(13 "F.Paste" user "Package Geometry/Pastemask Top")
		(15 "B.Paste" user "Package Geometry/Pastemask Bottom")
		(5 "F.SilkS" user "Ref Des/Silkscreen Top")
		(7 "B.SilkS" user "Ref Des/Silkscreen Bottom")
		(1 "F.Mask" user "Board Geometry/Soldermask Top")
		(3 "B.Mask" user "Board Geometry/Soldermask Bottom")
		(17 "Dwgs.User" user "User.Drawings")
		(19 "Cmts.User" user "User.Comments")
		(21 "Eco1.User" user "User.Eco1")
		(23 "Eco2.User" user "User.Eco2")
		(25 "Edge.Cuts" user "Board Geometry/Outline")
		(27 "Margin" user)
		(31 "F.CrtYd" user "Package Geometry/Place Bound Top")
		(29 "B.CrtYd" user "Package Geometry/Place Bound Bottom")
		(35 "F.Fab" user "Ref Des/Assembly Top")
		(33 "B.Fab" user "Ref Des/Assembly Bottom")
	)
	(footprint ""
		(layer "B.Cu")
		(at 11.961114 -98.296222 180)
		(property "Reference" "C2034"
			(at 0 0 0)
			(layer "B.SilkS")
			(hide yes)
			(effects
				(font
					(size 1.27 1.27)
				)
				(justify mirror)
			)
		)
		(property "Value" ""
			(at 0 0 0)
			(layer "B.Fab")
			(effects
				(font
					(size 1.27 1.27)
				)
				(justify mirror)
			)
		)
		(duplicate_pad_numbers_are_jumpers no)
		(fp_line
			(start 0.7874 0.4064)
			(end 0.7874 -0.4064)
			(stroke
				(width 0.1524)
				(type default)
			)
			(layer "B.SilkS")
		)
		(fp_line
			(start 0.7874 -0.4064)
			(end -0.7874 -0.4064)
			(stroke
				(width 0.1524)
				(type default)
			)
			(layer "B.SilkS")
		)
		(fp_line
			(start -0.7874 0.4064)
			(end 0.7874 0.4064)
			(stroke
				(width 0.1524)
				(type default)
			)
			(layer "B.SilkS")
		)
		(fp_line
			(start -0.7874 -0.4064)
			(end -0.7874 0.4064)
			(stroke
				(width 0.1524)
				(type default)
			)
			(layer "B.SilkS")
		)
		(fp_line
			(start 0.67945 0.3048)
			(end 0.67945 -0.305054)
			(stroke
				(width 0.1)
				(type default)
			)
			(layer "B.Fab")
		)
		(fp_line
			(start 0.67945 -0.305054)
			(end 0.12065 -0.305054)
			(stroke
				(width 0.1)
				(type default)
			)
			(layer "B.Fab")
		)
		(fp_line
			(start 0.12065 0.3048)
			(end 0.67945 0.3048)
			(stroke
				(width 0.1)
				(type default)
			)
			(layer "B.Fab")
		)
		(fp_line
			(start 0.12065 0.2794)
			(end 0.12065 0.3048)
			(stroke
				(width 0.1)
				(type default)
			)
			(layer "B.Fab")
		)
		(fp_line
			(start 0.12065 -0.2794)
			(end -0.12065 -0.2794)
			(stroke
				(width 0.1)
				(type default)
			)
			(layer "B.Fab")
		)
		(fp_line
			(start 0.12065 -0.305054)
			(end 0.12065 -0.2794)
			(stroke
				(width 0.1)
				(type default)
			)
			(layer "B.Fab")
		)
		(fp_line
			(start -0.120396 0.3048)
			(end -0.120396 0.2794)
			(stroke
				(width 0.1)
				(type default)
			)
			(layer "B.Fab")
		)
		(fp_line
			(start -0.120396 0.2794)
			(end 0.12065 0.2794)
			(stroke
				(width 0.1)
				(type default)
			)
			(layer "B.Fab")
		)
		(fp_line
			(start -0.12065 -0.2794)
			(end -0.12065 -0.3048)
			(stroke
				(width 0.1)
				(type default)
			)
			(layer "B.Fab")
		)
		(fp_line
			(start -0.12065 -0.3048)
			(end -0.67945 -0.3048)
			(stroke
				(width 0.1)
				(type default)
			)
			(layer "B.Fab")
		)
		(fp_line
			(start -0.67945 0.3048)
			(end -0.120396 0.3048)
			(stroke
				(width 0.1)
				(type default)
			)
			(layer "B.Fab")
		)
		(fp_line
			(start -0.67945 -0.3048)
			(end -0.67945 0.3048)
			(stroke
				(width 0.1)
				(type default)
			)
			(layer "B.Fab")
		)
		(pad "1" smd circle
			(at 0.40005 0)
			(size 0 0)
			(layers "B.Cu" "B.Mask" "B.Paste")
			(net "P3V3_AUX_USB_HUB")
		)
		(pad "2" smd circle
			(at -0.40005 0)
			(size 0 0)
			(layers "B.Cu" "B.Mask" "B.Paste")
			(net "GND")
		)
	)
	(footprint ""
		(layer "B.Cu")
		(at 435.145942 -8.316976 -90)
		(property "Reference" "R1895"
			(at 0 0 90)
			(layer "B.SilkS")
			(hide yes)
			(effects
				(font
					(size 1.27 1.27)
				)
				(justify mirror)
			)
		)
		(property "Value" ""
			(at 0 0 90)
			(layer "B.Fab")
			(effects
				(font
					(size 1.27 1.27)
				)
				(justify mirror)
			)
		)
		(duplicate_pad_numbers_are_jumpers no)
		(fp_line
			(start -0.7874 0.4064)
			(end 0.7874 0.4064)
			(stroke
				(width 0.1524)
				(type default)
			)
			(layer "B.SilkS")
		)
		(fp_line
			(start 0.7874 0.4064)
			(end 0.7874 -0.4064)
			(stroke
				(width 0.1524)
				(type default)
			)
			(layer "B.SilkS")
		)
		(fp_line
			(start -0.7874 -0.4064)
			(end -0.7874 0.4064)
			(stroke
				(width 0.1524)
				(type default)
			)
			(layer "B.SilkS")
		)
		(fp_line
			(start 0.7874 -0.4064)
			(end -0.7874 -0.4064)
			(stroke
				(width 0.1524)
				(type default)
			)
			(layer "B.SilkS")
		)
		(fp_line
			(start -0.67945 0.3048)
			(end -0.120396 0.3048)
			(stroke
				(width 0.1)
				(type default)
			)
			(layer "B.Fab")
		)
		(fp_line
			(start -0.120396 0.3048)
			(end -0.120396 0.2794)
			(stroke
				(width 0.1)
				(type default)
			)
			(layer "B.Fab")
		)
		(fp_line
			(start 0.12065 0.3048)
			(end 0.67945 0.3048)
			(stroke
				(width 0.1)
				(type default)
			)
			(layer "B.Fab")
		)
		(fp_line
			(start 0.67945 0.3048)
			(end 0.67945 -0.305054)
			(stroke
				(width 0.1)
				(type default)
			)
			(layer "B.Fab")
		)
		(fp_line
			(start -0.120396 0.2794)
			(end 0.12065 0.2794)
			(stroke
				(width 0.1)
				(type default)
			)
			(layer "B.Fab")
		)
		(fp_line
			(start 0.12065 0.2794)
			(end 0.12065 0.3048)
			(stroke
				(width 0.1)
				(type default)
			)
			(layer "B.Fab")
		)
		(fp_line
			(start -0.12065 -0.2794)
			(end -0.12065 -0.3048)
			(stroke
				(width 0.1)
				(type default)
			)
			(layer "B.Fab")
		)
		(fp_line
			(start 0.12065 -0.2794)
			(end -0.12065 -0.2794)
			(stroke
				(width 0.1)
				(type default)
			)
			(layer "B.Fab")
		)
		(fp_line
			(start -0.67945 -0.3048)
			(end -0.67945 0.3048)
			(stroke
				(width 0.1)
				(type default)
			)
			(layer "B.Fab")
		)
		(fp_line
			(start -0.12065 -0.3048)
			(end -0.67945 -0.3048)
			(stroke
				(width 0.1)
				(type default)
			)
			(layer "B.Fab")
		)
		(fp_line
			(start 0.12065 -0.305054)
			(end 0.12065 -0.2794)
			(stroke
				(width 0.1)
				(type default)
			)
			(layer "B.Fab")
		)
		(fp_line
			(start 0.67945 -0.305054)
			(end 0.12065 -0.305054)
			(stroke
				(width 0.1)
				(type default)
			)
			(layer "B.Fab")
		)
		(pad "1" smd circle
			(at 0.40005 0 90)
			(size 0 0)
			(layers "B.Cu" "B.Mask" "B.Paste")
			(net "OCP_SFF_PRSNTA_R_N")
		)
		(pad "2" smd circle
			(at -0.40005 0 90)
			(size 0 0)
			(layers "B.Cu" "B.Mask" "B.Paste")
			(net "GND")
		)
	)
)
